# BASEBOARD_FAB2 (Tioga Pass) — schematic netlist excerpt (pin names and nets, part order shuffled) for the footprints in the layout excerpt that follows; sources: Cadence DE-HDL packaged netlist, KiCad conversion of Wiwynn_Tioga_Pass_MB.brd

EU4D6  IR354XX  IR35411 IC  pkg SM  page 202
  VOS  = PVCCIN_CPU0
  LGND  = GND
  VCC  = VR_PVCCIN_CPU0_PH2_VCIN
  VDRV  = P5V_STBY
  PGND(0)  = GND
  GL(0)  = TP_PVCCIN_CPU0_PH2_GL_0
  PGND(1)  = GND
  SW  = VR_PVCCIN_CPU0_PHASE2
  VIN(0)  = VR_FET_SW_P12V_STBY_PVCCIN_CPU0
  VIN(1)  = VR_FET_SW_P12V_STBY_PVCCIN_CPU0
  NC  = NC
  PHASE  = VR_PVCCIN_CPU0_PH2_PHASE
  BOOST  = VR_PVCCIN_CPU0_PH2_BOOT_R
  PWM  = VR_PVCCIN_CPU0_PWM2
  EN  = P5V_STBY
  TOUT_FLT  = A_TSENSE_PVCCIN_CPU0
  OCSET  = VR_PVCCIN_CPU0_PH2_OCSET
  IOUT  = ISENSE_PVCCIN_CPU0_PH2_IMON
  REFIN  = VR_PVCCIN_CPU0_AIREF2
  PGND(2)  = GND
  GL(1)  = TP_PVCCIN_CPU0_PH2_GL_1

(kicad_pcb
	(version 20260206)
	(generator "pcbnew")
	(generator_version "10.0")
	(general
		(thickness 1.6)
		(legacy_teardrops no)
	)
	(paper "A4")
	(title_block
		(title "Wiwynn_Tioga_Pass_MB.brd")
		(comment 1 "Tioga Pass / footprints 864-864 of 4770")
	)
	(layers
		(0 "F.Cu" signal "TOP")
		(4 "In1.Cu" signal "L2GND")
		(6 "In2.Cu" signal "L3")
		(8 "In3.Cu" signal "L4GND")
		(10 "In4.Cu" signal "L5")
		(12 "In5.Cu" signal "L6GND")
		(14 "In6.Cu" signal "L7VCC")
		(16 "In7.Cu" signal "L8VCC")
		(18 "In8.Cu" signal "L9GND")
		(20 "In9.Cu" signal "L10")
		(22 "In10.Cu" signal "L11GND")
		(24 "In11.Cu" signal "L12")
		(26 "In12.Cu" signal "L13GND")
		(2 "B.Cu" signal "BOTTOM")
		(9 "F.Adhes" user "F.Adhesive")
		(11 "B.Adhes" user "B.Adhesive")
		(13 "F.Paste" user "Package Geometry/Pastemask Top")
		(15 "B.Paste" user "Package Geometry/Pastemask Bottom")
		(5 "F.SilkS" user "Ref Des/Silkscreen Top")
		(7 "B.SilkS" user "Ref Des/Silkscreen Bottom")
		(1 "F.Mask" user "Board Geometry/Soldermask Top")
		(3 "B.Mask" user "Board Geometry/Soldermask Bottom")
		(17 "Dwgs.User" user "User.Drawings")
		(19 "Cmts.User" user "User.Comments")
		(21 "Eco1.User" user "User.Eco1")
		(23 "Eco2.User" user "User.Eco2")
		(25 "Edge.Cuts" user "Board Geometry/Outline")
		(27 "Margin" user)
		(31 "F.CrtYd" user "Package Geometry/Place Bound Top")
		(29 "B.CrtYd" user "Package Geometry/Place Bound Bottom")
		(35 "F.Fab" user "Ref Des/Assembly Top")
		(33 "B.Fab" user "Ref Des/Assembly Bottom")
	)
	(footprint ""
		(layer "F.Cu")
		(at 198.925434 -65.167764 90)
		(property "Reference" "EU4D6"
			(at 3.334766 -1.542034 0)
			(unlocked yes)
			(layer "F.SilkS")
			(effects
				(font
					(size 0.7874 0.5842)
					(thickness 0.1524)
				)
			)
		)
		(property "Value" ""
			(at 0 0 90)
			(layer "F.Fab")
			(effects
				(font
					(size 1.27 1.27)
				)
			)
		)
		(duplicate_pad_numbers_are_jumpers no)
		(fp_line
			(start 2.9718 -3.5052)
			(end 2.9718 3.429)
			(stroke
				(width 0.1524)
				(type default)
			)
			(layer "F.SilkS")
		)
		(fp_line
			(start -3.0099 -3.5052)
			(end 2.9718 -3.5052)
			(stroke
				(width 0.1524)
				(type default)
			)
			(layer "F.SilkS")
		)
		(fp_line
			(start 2.9718 3.429)
			(end -3.0099 3.429)
			(stroke
				(width 0.1524)
				(type default)
			)
			(layer "F.SilkS")
		)
		(fp_line
			(start -3.0099 3.429)
			(end -3.0099 -3.5052)
			(stroke
				(width 0.1524)
				(type default)
			)
			(layer "F.SilkS")
		)
		(fp_circle
			(center -3.057398 -2.678684)
			(end -3.057398 -2.551684)
			(stroke
				(width 0.254)
				(type default)
			)
			(fill no)
			(layer "F.SilkS")
		)
		(fp_poly
			(pts
				(xy -2.9972 -3.4925) (xy -2.9972 -2.6924) (xy -2.1971 -3.4925)
			)
			(stroke
				(width 0)
				(type default)
			)
			(fill yes)
			(layer "F.SilkS")
		)
		(fp_poly
			(pts
				(xy -2.549906 -3.050032) (xy -2.549906 3.050032) (xy 2.549906 3.050032) (xy 2.549906 -3.050032)
			)
			(stroke
				(width 0)
				(type default)
			)
			(fill no)
			(layer "F.CrtYd")
		)
		(fp_line
			(start 2.549906 -3.050032)
			(end 2.549906 3.050032)
			(stroke
				(width 0.1)
				(type default)
			)
			(layer "F.Fab")
		)
		(fp_line
			(start -2.549906 -3.050032)
			(end 2.549906 -3.050032)
			(stroke
				(width 0.1)
				(type default)
			)
			(layer "F.Fab")
		)
		(fp_line
			(start 2.549906 3.050032)
			(end -2.549906 3.050032)
			(stroke
				(width 0.1)
				(type default)
			)
			(layer "F.Fab")
		)
		(fp_line
			(start -2.549906 3.050032)
			(end -2.549906 -3.050032)
			(stroke
				(width 0.1)
				(type default)
			)
			(layer "F.Fab")
		)
		(fp_circle
			(center -3.057398 -2.678684)
			(end -3.057398 -2.551684)
			(stroke
				(width 0.254)
				(type default)
			)
			(fill no)
			(layer "F.Fab")
		)
		(pad "1" smd rect
			(at -2.39522 -2.279904 90)
			(size 0.7112 0.254)
			(layers "F.Cu" "F.Mask" "F.Paste")
			(net "PVCCIN_CPU0")
		)
		(pad "2" smd rect
			(at -2.39522 -1.83007 90)
			(size 0.7112 0.254)
			(layers "F.Cu" "F.Mask" "F.Paste")
			(net "GND")
		)
		(pad "3" smd rect
			(at -2.39522 -1.379982 90)
			(size 0.7112 0.254)
			(layers "F.Cu" "F.Mask" "F.Paste")
			(net "VR_PVCCIN_CPU0_PH2_VCIN")
		)
		(pad "4" smd rect
			(at -2.39522 -0.929894 90)
			(size 0.7112 0.254)
			(layers "F.Cu" "F.Mask" "F.Paste")
			(net "P5V_STBY")
		)
		(pad "5" smd rect
			(at -2.39522 -0.48006 90)
			(size 0.7112 0.254)
			(layers "F.Cu" "F.Mask" "F.Paste")
			(net "GND")
		)
		(pad "6" smd rect
			(at -2.39522 -0.029972 90)
			(size 0.7112 0.254)
			(layers "F.Cu" "F.Mask" "F.Paste")
			(net "TP_PVCCIN_CPU0_PH2_GL_0")
		)
		(pad "7" smd custom
			(at 0.016764 1.145032 90)
			(size 0.53975 0.53975)
			(layers "F.Cu" "F.Mask" "F.Paste")
			(net "GND")
			(options
				(clearance outline)
				(anchor circle)
			)
			(primitives
				(gr_poly
					(pts
						(xy -2.7051 1.0795) (xy -2.7051 -0.3683) (xy -0.9271 -0.3683) (xy -0.9271 -1.0795) (xy 2.7051 -1.0795)
						(xy 2.7051 1.0795)
					)
					(width 0)
					(fill yes)
				)
			)
		)
		(pad "10" smd rect
			(at -0.008382 2.874772 90)
			(size 4.3434 0.6096)
			(layers "F.Cu" "F.Mask" "F.Paste")
			(net "VR_PVCCIN_CPU0_PHASE2")
		)
		(pad "25" smd rect
			(at 1.548384 -1.283208 90)
			(size 2.3368 2.0066)
			(layers "F.Cu" "F.Mask" "F.Paste")
			(net "VR_FET_SW_P12V_STBY_PVCCIN_CPU0")
		)
		(pad "30" smd rect
			(at 2.050034 -2.895092 90)
			(size 0.254 0.7112)
			(layers "F.Cu" "F.Mask" "F.Paste")
			(net "VR_FET_SW_P12V_STBY_PVCCIN_CPU0")
		)
		(pad "31" smd rect
			(at 1.599946 -2.895092 90)
			(size 0.254 0.7112)
			(layers "F.Cu" "F.Mask" "F.Paste")
			(net "Net_362")
		)
		(pad "32" smd rect
			(at 1.150112 -2.895092 90)
			(size 0.254 0.7112)
			(layers "F.Cu" "F.Mask" "F.Paste")
			(net "VR_PVCCIN_CPU0_PH2_PHASE")
		)
		(pad "33" smd rect
			(at 0.700024 -2.895092 90)
			(size 0.254 0.7112)
			(layers "F.Cu" "F.Mask" "F.Paste")
			(net "VR_PVCCIN_CPU0_PH2_BOOT_R")
		)
		(pad "34" smd rect
			(at 0.249936 -2.895092 90)
			(size 0.254 0.7112)
			(layers "F.Cu" "F.Mask" "F.Paste")
			(net "VR_PVCCIN_CPU0_PWM2")
		)
		(pad "35" smd rect
			(at -0.199898 -2.895092 90)
			(size 0.254 0.7112)
			(layers "F.Cu" "F.Mask" "F.Paste")
			(net "P5V_STBY")
		)
		(pad "36" smd rect
			(at -0.649986 -2.895092 90)
			(size 0.254 0.7112)
			(layers "F.Cu" "F.Mask" "F.Paste")
			(net "A_TSENSE_PVCCIN_CPU0")
		)
		(pad "37" smd rect
			(at -1.100074 -2.895092 90)
			(size 0.254 0.7112)
			(layers "F.Cu" "F.Mask" "F.Paste")
			(net "VR_PVCCIN_CPU0_PH2_OCSET")
		)
		(pad "38" smd rect
			(at -1.549908 -2.895092 90)
			(size 0.254 0.7112)
			(layers "F.Cu" "F.Mask" "F.Paste")
			(net "ISENSE_PVCCIN_CPU0_PH2_IMON")
		)
		(pad "39" smd rect
			(at -1.999996 -2.895092 90)
			(size 0.254 0.7112)
			(layers "F.Cu" "F.Mask" "F.Paste")
			(net "VR_PVCCIN_CPU0_AIREF2")
		)
		(pad "40" smd rect
			(at -0.871728 -1.283208 90)
			(size 1.8034 2.0066)
			(layers "F.Cu" "F.Mask" "F.Paste")
			(net "GND")
		)
		(pad "41" smd rect
			(at -1.533906 0.247904 90)
			(size 0.508 0.3556)
			(layers "F.Cu" "F.Mask" "F.Paste")
			(net "TP_PVCCIN_CPU0_PH2_GL_1")
		)
	)
)
